(kicad_pcb
	(version 20260206)
	(generator "pcbnew")
	(generator_version "10.0")
	(general
		(thickness 1.6)
		(legacy_teardrops no)
	)
	(paper "A4")
	(title_block
		(title "fcb — Lightning_FCB_BRD.brd")
		(comment 1 "Lightning (Wiwynn / Facebook NVMe JBOF) / footprints 83-88 of 495")
	)
	(layers
		(0 "F.Cu" signal "TOP")
		(4 "In1.Cu" signal "L2GND")
		(6 "In2.Cu" signal "L3VCC")
		(2 "B.Cu" signal "BOTTOM")
		(9 "F.Adhes" user "F.Adhesive")
		(11 "B.Adhes" user "B.Adhesive")
		(13 "F.Paste" user "Package Geometry/Pastemask Top")
		(15 "B.Paste" user "Package Geometry/Pastemask Bottom")
		(5 "F.SilkS" user "Ref Des/Silkscreen Top")
		(7 "B.SilkS" user "Ref Des/Silkscreen Bottom")
		(1 "F.Mask" user "Board Geometry/Soldermask Top")
		(3 "B.Mask" user "Board Geometry/Soldermask Bottom")
		(17 "Dwgs.User" user "User.Drawings")
		(19 "Cmts.User" user "User.Comments")
		(21 "Eco1.User" user "User.Eco1")
		(23 "Eco2.User" user "User.Eco2")
		(25 "Edge.Cuts" user "Board Geometry/Outline")
		(27 "Margin" user)
		(31 "F.CrtYd" user "Package Geometry/Place Bound Top")
		(29 "B.CrtYd" user "Package Geometry/Place Bound Bottom")
		(35 "F.Fab" user "Ref Des/Assembly Top")
		(33 "B.Fab" user "Ref Des/Assembly Bottom")
	)
	(footprint ""
		(layer "F.Cu")
		(at 33.2232 -248.5644)
		(property "Reference" "C20"
			(at 0 0 0)
			(layer "F.SilkS")
			(hide yes)
			(effects
				(font
					(size 1.27 1.27)
				)
			)
		)
		(property "Value" "SCD1U50V3KX-GP"
			(at 0 -2.8194 0)
			(unlocked yes)
			(layer "F.Fab")
			(hide yes)
			(effects
				(font
					(size 1.016 1.016)
					(thickness 0.1524)
				)
			)
		)
		(property "Device Type" "C603H36"
			(at 0 -4.3434 0)
			(unlocked yes)
			(layer "F.Fab")
			(hide yes)
			(effects
				(font
					(size 1.016 1.016)
					(thickness 0.1524)
				)
			)
		)
		(duplicate_pad_numbers_are_jumpers no)
		(fp_line
			(start 0.508 0)
			(end -0.508 0)
			(stroke
				(width 0.2032)
				(type default)
			)
			(layer "F.SilkS")
		)
		(fp_rect
			(start -0.5842 1.3335)
			(end 0.5842 -1.3335)
			(stroke
				(width 0)
				(type default)
			)
			(fill no)
			(layer "F.CrtYd")
		)
		(fp_rect
			(start -0.5842 1.3335)
			(end 0.5842 -1.3335)
			(stroke
				(width 0)
				(type default)
			)
			(fill no)
			(layer "F.Fab")
		)
		(pad "1" smd custom
			(at 0 -0.762)
			(size 0.2159 0.2159)
			(layers "F.Cu" "F.Mask" "F.Paste")
			(net "P3V3")
			(options
				(clearance outline)
				(anchor circle)
			)
			(primitives
				(gr_poly
					(pts
						(arc
							(start -0.3302 -0.4318)
							(mid -0.402042 -0.402042)
							(end -0.4318 -0.3302)
						)
						(arc
							(start -0.4318 0.3302)
							(mid -0.402042 0.402042)
							(end -0.3302 0.4318)
						)
						(arc
							(start 0.3302 0.4318)
							(mid 0.402042 0.402042)
							(end 0.4318 0.3302)
						)
						(arc
							(start 0.4318 -0.3302)
							(mid 0.402042 -0.402042)
							(end 0.3302 -0.4318)
						)
					)
					(width 0)
					(fill yes)
				)
			)
		)
		(pad "2" smd custom
			(at 0 0.762)
			(size 0.2159 0.2159)
			(layers "F.Cu" "F.Mask" "F.Paste")
			(net "GND")
			(options
				(clearance outline)
				(anchor circle)
			)
			(primitives
				(gr_poly
					(pts
						(arc
							(start -0.3302 -0.4318)
							(mid -0.402042 -0.402042)
							(end -0.4318 -0.3302)
						)
						(arc
							(start -0.4318 0.3302)
							(mid -0.402042 0.402042)
							(end -0.3302 0.4318)
						)
						(arc
							(start 0.3302 0.4318)
							(mid 0.402042 0.402042)
							(end 0.4318 0.3302)
						)
						(arc
							(start 0.4318 -0.3302)
							(mid 0.402042 -0.402042)
							(end 0.3302 -0.4318)
						)
					)
					(width 0)
					(fill yes)
				)
			)
		)
	)
	(footprint ""
		(layer "F.Cu")
		(at 31.122366 -242.327176)
		(property "Reference" "R44"
			(at 0 0 0)
			(layer "F.SilkS")
			(hide yes)
			(effects
				(font
					(size 1.27 1.27)
				)
			)
		)
		(property "Value" "4K7R2J-2-GP"
			(at 0.064008 -3.993896 0)
			(unlocked yes)
			(layer "F.Fab")
			(hide yes)
			(effects
				(font
					(size 1.016 1.016)
					(thickness 0.1524)
				)
			)
		)
		(property "Device Type" "R402H16"
			(at 0.064008 -5.517896 0)
			(unlocked yes)
			(layer "F.Fab")
			(hide yes)
			(effects
				(font
					(size 1.016 1.016)
					(thickness 0.1524)
				)
			)
		)
		(duplicate_pad_numbers_are_jumpers no)
		(fp_line
			(start -0.508 -0.9398)
			(end -0.508 0.9398)
			(stroke
				(width 0.1524)
				(type default)
			)
			(layer "F.SilkS")
		)
		(fp_line
			(start 0.508 -0.9398)
			(end -0.508 -0.9398)
			(stroke
				(width 0.1524)
				(type default)
			)
			(layer "F.SilkS")
		)
		(fp_rect
			(start -0.508 0.9398)
			(end 0.508 -0.9398)
			(stroke
				(width 0)
				(type default)
			)
			(fill no)
			(layer "F.CrtYd")
		)
		(fp_rect
			(start -0.508 0.9398)
			(end 0.508 -0.9398)
			(stroke
				(width 0)
				(type default)
			)
			(fill no)
			(layer "F.Fab")
		)
		(pad "1" smd custom
			(at 0 -0.4445)
			(size 0.1397 0.1397)
			(layers "F.Cu" "F.Mask" "F.Paste")
			(net "FCB_EEPROM_A2")
			(options
				(clearance outline)
				(anchor circle)
			)
			(primitives
				(gr_poly
					(pts
						(arc
							(start -0.1778 -0.2794)
							(mid -0.249642 -0.249642)
							(end -0.2794 -0.1778)
						)
						(arc
							(start -0.2794 0.1778)
							(mid -0.249642 0.249642)
							(end -0.1778 0.2794)
						)
						(arc
							(start 0.1778 0.2794)
							(mid 0.249642 0.249642)
							(end 0.2794 0.1778)
						)
						(arc
							(start 0.2794 -0.1778)
							(mid 0.249642 -0.249642)
							(end 0.1778 -0.2794)
						)
					)
					(width 0)
					(fill yes)
				)
			)
		)
		(pad "2" smd custom
			(at 0 0.4445)
			(size 0.1397 0.1397)
			(layers "F.Cu" "F.Mask" "F.Paste")
			(net "GND")
			(options
				(clearance outline)
				(anchor circle)
			)
			(primitives
				(gr_poly
					(pts
						(arc
							(start -0.1778 -0.2794)
							(mid -0.249642 -0.249642)
							(end -0.2794 -0.1778)
						)
						(arc
							(start -0.2794 0.1778)
							(mid -0.249642 0.249642)
							(end -0.1778 0.2794)
						)
						(arc
							(start 0.1778 0.2794)
							(mid 0.249642 0.249642)
							(end 0.2794 0.1778)
						)
						(arc
							(start 0.2794 -0.1778)
							(mid 0.249642 -0.249642)
							(end 0.1778 -0.2794)
						)
					)
					(width 0)
					(fill yes)
				)
			)
		)
	)
	(footprint ""
		(layer "F.Cu")
		(at 12.6746 -225.8822 180)
		(property "Reference" "R124"
			(at 0 0 180)
			(layer "F.SilkS")
			(hide yes)
			(effects
				(font
					(size 1.27 1.27)
				)
			)
		)
		(property "Value" "1K8R6J-GP"
			(at -0.0508 -4.8514 180)
			(unlocked yes)
			(layer "F.Fab")
			(hide yes)
			(effects
				(font
					(size 1.016 1.016)
					(thickness 0.1524)
				)
			)
		)
		(property "Device Type" "R1206H28"
			(at 0 -6.3754 180)
			(unlocked yes)
			(layer "F.Fab")
			(hide yes)
			(effects
				(font
					(size 1.016 1.016)
					(thickness 0.1524)
				)
			)
		)
		(duplicate_pad_numbers_are_jumpers no)
		(fp_line
			(start 1.016 2.2352)
			(end -1.016 2.2352)
			(stroke
				(width 0.1524)
				(type default)
			)
			(layer "F.SilkS")
		)
		(fp_line
			(start 1.016 -2.2352)
			(end 1.016 2.2352)
			(stroke
				(width 0.1524)
				(type default)
			)
			(layer "F.SilkS")
		)
		(fp_line
			(start -1.016 2.2352)
			(end -1.016 -2.2352)
			(stroke
				(width 0.1524)
				(type default)
			)
			(layer "F.SilkS")
		)
		(fp_line
			(start -1.016 -2.2352)
			(end 1.016 -2.2352)
			(stroke
				(width 0.1524)
				(type default)
			)
			(layer "F.SilkS")
		)
		(fp_rect
			(start -1.0922 2.3114)
			(end 1.0922 -2.3114)
			(stroke
				(width 0)
				(type default)
			)
			(fill no)
			(layer "F.CrtYd")
		)
		(fp_poly
			(pts
				(xy -1.0922 -2.3114) (xy 1.0922 -2.3114) (xy 1.0922 2.3114) (xy -1.0922 2.3114)
			)
			(stroke
				(width 0)
				(type default)
			)
			(fill no)
			(layer "F.Fab")
		)
		(pad "1" smd rect
			(at 0 -1.397 180)
			(size 1.651 1.27)
			(layers "F.Cu" "F.Mask" "F.Paste")
			(net "P12V")
		)
		(pad "2" smd rect
			(at 0 1.397 180)
			(size 1.651 1.27)
			(layers "F.Cu" "F.Mask" "F.Paste")
			(net "LED_DR_LED3_BLUE")
		)
	)
	(footprint ""
		(layer "F.Cu")
		(at 7.141972 -277.643082 90)
		(property "Reference" "Q6"
			(at 0 0 90)
			(layer "F.SilkS")
			(hide yes)
			(effects
				(font
					(size 1.27 1.27)
				)
			)
		)
		(property "Value" "PMBS3904-1-GP"
			(at 0 -9.0932 90)
			(unlocked yes)
			(layer "F.Fab")
			(hide yes)
			(effects
				(font
					(size 1.016 1.016)
					(thickness 0.1524)
				)
			)
		)
		(property "Device Type" "SOT-23-10H44"
			(at 0 -10.6172 90)
			(unlocked yes)
			(layer "F.Fab")
			(hide yes)
			(effects
				(font
					(size 1.016 1.016)
					(thickness 0.1524)
				)
			)
		)
		(duplicate_pad_numbers_are_jumpers no)
		(fp_line
			(start 1.651 -1.778)
			(end -1.651 -1.778)
			(stroke
				(width 0.1524)
				(type default)
			)
			(layer "F.SilkS")
		)
		(fp_line
			(start -1.651 -1.778)
			(end -1.651 1.778)
			(stroke
				(width 0.1524)
				(type default)
			)
			(layer "F.SilkS")
		)
		(fp_line
			(start 1.651 1.778)
			(end 1.651 -1.778)
			(stroke
				(width 0.1524)
				(type default)
			)
			(layer "F.SilkS")
		)
		(fp_line
			(start -1.651 1.778)
			(end 1.651 1.778)
			(stroke
				(width 0.1524)
				(type default)
			)
			(layer "F.SilkS")
		)
		(fp_line
			(start -0.9906 1.86309)
			(end -0.701294 2.15265)
			(stroke
				(width 0.0127)
				(type default)
			)
			(layer "F.SilkS")
		)
		(fp_line
			(start -0.994156 1.8669)
			(end -0.987044 1.8669)
			(stroke
				(width 0.0127)
				(type default)
			)
			(layer "F.SilkS")
		)
		(fp_line
			(start -1.003808 1.876552)
			(end -0.977646 1.876552)
			(stroke
				(width 0.0127)
				(type default)
			)
			(layer "F.SilkS")
		)
		(fp_line
			(start -0.635 1.8796)
			(end -1.7526 1.8796)
			(stroke
				(width 0.3302)
				(type default)
			)
			(layer "F.SilkS")
		)
		(fp_line
			(start -1.7526 1.8796)
			(end -1.7526 0.9906)
			(stroke
				(width 0.3302)
				(type default)
			)
			(layer "F.SilkS")
		)
		(fp_line
			(start -1.013206 1.88595)
			(end -0.967994 1.88595)
			(stroke
				(width 0.0127)
				(type default)
			)
			(layer "F.SilkS")
		)
		(fp_line
			(start -1.022858 1.895602)
			(end -0.958596 1.895602)
			(stroke
				(width 0.0127)
				(type default)
			)
			(layer "F.SilkS")
		)
		(fp_line
			(start -1.032256 1.905)
			(end -0.948944 1.905)
			(stroke
				(width 0.0127)
				(type default)
			)
			(layer "F.SilkS")
		)
		(fp_line
			(start -1.041908 1.914652)
			(end -0.939546 1.914652)
			(stroke
				(width 0.0127)
				(type default)
			)
			(layer "F.SilkS")
		)
		(fp_line
			(start -1.051306 1.92405)
			(end -0.929894 1.92405)
			(stroke
				(width 0.0127)
				(type default)
			)
			(layer "F.SilkS")
		)
		(fp_line
			(start -1.060958 1.933702)
			(end -0.920496 1.933702)
			(stroke
				(width 0.0127)
				(type default)
			)
			(layer "F.SilkS")
		)
		(fp_line
			(start -1.070356 1.9431)
			(end -0.910844 1.9431)
			(stroke
				(width 0.0127)
				(type default)
			)
			(layer "F.SilkS")
		)
		(fp_line
			(start -1.080008 1.952752)
			(end -0.901446 1.952752)
			(stroke
				(width 0.0127)
				(type default)
			)
			(layer "F.SilkS")
		)
		(fp_line
			(start -1.089406 1.96215)
			(end -0.891794 1.96215)
			(stroke
				(width 0.0127)
				(type default)
			)
			(layer "F.SilkS")
		)
		(fp_line
			(start -1.099058 1.971802)
			(end -0.882396 1.971802)
			(stroke
				(width 0.0127)
				(type default)
			)
			(layer "F.SilkS")
		)
		(fp_line
			(start -1.108456 1.9812)
			(end -0.872744 1.9812)
			(stroke
				(width 0.0127)
				(type default)
			)
			(layer "F.SilkS")
		)
		(fp_line
			(start -1.118108 1.990852)
			(end -0.863346 1.990852)
			(stroke
				(width 0.0127)
				(type default)
			)
			(layer "F.SilkS")
		)
		(fp_line
			(start -1.127506 2.00025)
			(end -0.853694 2.00025)
			(stroke
				(width 0.0127)
				(type default)
			)
			(layer "F.SilkS")
		)
		(fp_line
			(start -1.137158 2.009902)
			(end -0.844296 2.009902)
			(stroke
				(width 0.0127)
				(type default)
			)
			(layer "F.SilkS")
		)
		(fp_line
			(start -1.146556 2.0193)
			(end -0.834644 2.0193)
			(stroke
				(width 0.0127)
				(type default)
			)
			(layer "F.SilkS")
		)
		(fp_line
			(start -1.156208 2.028952)
			(end -0.825246 2.028952)
			(stroke
				(width 0.0127)
				(type default)
			)
			(layer "F.SilkS")
		)
		(fp_line
			(start -1.165606 2.03835)
			(end -0.815594 2.03835)
			(stroke
				(width 0.0127)
				(type default)
			)
			(layer "F.SilkS")
		)
		(fp_line
			(start -1.175258 2.048002)
			(end -0.806196 2.048002)
			(stroke
				(width 0.0127)
				(type default)
			)
			(layer "F.SilkS")
		)
		(fp_line
			(start -1.184656 2.0574)
			(end -0.796544 2.0574)
			(stroke
				(width 0.0127)
				(type default)
			)
			(layer "F.SilkS")
		)
		(fp_line
			(start -1.194308 2.067052)
			(end -0.787146 2.067052)
			(stroke
				(width 0.0127)
				(type default)
			)
			(layer "F.SilkS")
		)
		(fp_line
			(start -1.203706 2.07645)
			(end -0.777494 2.07645)
			(stroke
				(width 0.0127)
				(type default)
			)
			(layer "F.SilkS")
		)
		(fp_line
			(start -1.213358 2.086102)
			(end -0.768096 2.086102)
			(stroke
				(width 0.0127)
				(type default)
			)
			(layer "F.SilkS")
		)
		(fp_line
			(start -1.222756 2.0955)
			(end -0.758444 2.0955)
			(stroke
				(width 0.0127)
				(type default)
			)
			(layer "F.SilkS")
		)
		(fp_line
			(start -1.232408 2.105152)
			(end -0.749046 2.105152)
			(stroke
				(width 0.0127)
				(type default)
			)
			(layer "F.SilkS")
		)
		(fp_line
			(start -1.241806 2.11455)
			(end -0.739394 2.11455)
			(stroke
				(width 0.0127)
				(type default)
			)
			(layer "F.SilkS")
		)
		(fp_line
			(start -1.251458 2.124202)
			(end -0.729996 2.124202)
			(stroke
				(width 0.0127)
				(type default)
			)
			(layer "F.SilkS")
		)
		(fp_line
			(start -1.260856 2.1336)
			(end -0.720344 2.1336)
			(stroke
				(width 0.0127)
				(type default)
			)
			(layer "F.SilkS")
		)
		(fp_line
			(start -0.719074 2.145538)
			(end -1.265936 2.14122)
			(stroke
				(width 0.0127)
				(type default)
			)
			(layer "F.SilkS")
		)
		(fp_line
			(start -1.279398 2.152142)
			(end -0.9906 1.86309)
			(stroke
				(width 0.0127)
				(type default)
			)
			(layer "F.SilkS")
		)
		(fp_line
			(start -0.71628 2.15265)
			(end -1.26492 2.15265)
			(stroke
				(width 0.0127)
				(type default)
			)
			(layer "F.SilkS")
		)
		(fp_line
			(start -1.279144 2.15265)
			(end -0.701294 2.15265)
			(stroke
				(width 0.0127)
				(type default)
			)
			(layer "F.SilkS")
		)
		(fp_poly
			(pts
				(xy -1.285748 2.159) (xy -1.285748 1.8796) (xy -1.778 1.8796) (xy -1.778 -1.8796) (xy 1.778 -1.8796)
				(xy 1.778 1.8796) (xy -0.694944 1.8796) (xy -0.694944 2.159)
			)
			(stroke
				(width 0)
				(type default)
			)
			(fill no)
			(layer "F.CrtYd")
		)
		(fp_poly
			(pts
				(xy -1.285748 2.159) (xy -1.285748 1.8796) (xy -1.778 1.8796) (xy -1.778 -1.8796) (xy 1.778 -1.8796)
				(xy 1.778 1.8796) (xy -0.694944 1.8796) (xy -0.694944 2.159)
			)
			(stroke
				(width 0)
				(type default)
			)
			(fill no)
			(layer "F.Fab")
		)
		(pad "1" smd rect
			(at -0.98425 0.9525 90)
			(size 0.762 1.143)
			(layers "F.Cu" "F.Mask" "F.Paste")
			(net "LED_DR_LED2_B")
		)
		(pad "2" smd rect
			(at 0.98425 0.9525 90)
			(size 0.762 1.143)
			(layers "F.Cu" "F.Mask" "F.Paste")
			(net "GND")
		)
		(pad "3" smd rect
			(at 0 -0.9525 90)
			(size 0.762 1.143)
			(layers "F.Cu" "F.Mask" "F.Paste")
			(net "LED_DR_LED2_BLUE")
		)
	)
	(footprint ""
		(layer "F.Cu")
		(at 20.3454 -481.5586)
		(property "Reference" "R177"
			(at 0 0 0)
			(layer "F.SilkS")
			(hide yes)
			(effects
				(font
					(size 1.27 1.27)
				)
			)
		)
		(property "Value" "0R1206-PAD-1-GP"
			(at 0 -5.0292 0)
			(unlocked yes)
			(layer "F.Fab")
			(hide yes)
			(effects
				(font
					(size 1.016 1.016)
					(thickness 0.1524)
				)
			)
		)
		(property "Device Type" "0R1206-PAD-1"
			(at 0 -6.5532 0)
			(unlocked yes)
			(layer "F.Fab")
			(hide yes)
			(effects
				(font
					(size 1.016 1.016)
					(thickness 0.1524)
				)
			)
		)
		(duplicate_pad_numbers_are_jumpers no)
		(fp_line
			(start -1.016 -2.2352)
			(end -1.016 2.2352)
			(stroke
				(width 0.1524)
				(type default)
			)
			(layer "F.SilkS")
		)
		(fp_line
			(start -1.016 2.2352)
			(end 1.016 2.2352)
			(stroke
				(width 0.1524)
				(type default)
			)
			(layer "F.SilkS")
		)
		(fp_line
			(start 1.016 -2.2352)
			(end -1.016 -2.2352)
			(stroke
				(width 0.1524)
				(type default)
			)
			(layer "F.SilkS")
		)
		(fp_line
			(start 1.016 2.2352)
			(end 1.016 -2.2352)
			(stroke
				(width 0.1524)
				(type default)
			)
			(layer "F.SilkS")
		)
		(fp_rect
			(start -1.0922 2.3114)
			(end 1.0922 -2.3114)
			(stroke
				(width 0)
				(type default)
			)
			(fill no)
			(layer "F.CrtYd")
		)
		(fp_poly
			(pts
				(xy -1.0922 -2.3114) (xy 1.0922 -2.3114) (xy 1.0922 2.3114) (xy -1.0922 2.3114)
			)
			(stroke
				(width 0)
				(type default)
			)
			(fill no)
			(layer "F.Fab")
		)
		(pad "1" smd rect
			(at 0 -1.397)
			(size 1.651 2.0574)
			(drill
				(offset 0 0.3937)
			)
			(layers "F.Cu" "F.Mask" "F.Paste")
			(net "P12V_FAN1")
		)
		(pad "2" smd rect
			(at 0 1.397)
			(size 1.651 2.0574)
			(drill
				(offset 0 -0.3937)
			)
			(layers "F.Cu" "F.Mask" "F.Paste")
			(net "P12V")
		)
	)
	(footprint ""
		(layer "F.Cu")
		(at 17.831308 -287.451038)
		(property "Reference" "D9"
			(at 0 0 0)
			(layer "F.SilkS")
			(hide yes)
			(effects
				(font
					(size 1.27 1.27)
				)
			)
		)
		(property "Value" "BAS16H-GP"
			(at 0 -5.5372 0)
			(unlocked yes)
			(layer "F.Fab")
			(hide yes)
			(effects
				(font
					(size 1.016 1.016)
					(thickness 0.1524)
				)
			)
		)
		(property "Device Type" "SOD123AKH48"
			(at 0 -7.0612 0)
			(unlocked yes)
			(layer "F.Fab")
			(hide yes)
			(effects
				(font
					(size 1.016 1.016)
					(thickness 0.1524)
				)
			)
		)
		(duplicate_pad_numbers_are_jumpers no)
		(fp_line
			(start -1.016 -2.667)
			(end -1.016 2.667)
			(stroke
				(width 0.1524)
				(type default)
			)
			(layer "F.SilkS")
		)
		(fp_line
			(start -1.016 2.667)
			(end 1.016 2.667)
			(stroke
				(width 0.1524)
				(type default)
			)
			(layer "F.SilkS")
		)
		(fp_line
			(start 0.889 2.921)
			(end -0.889 2.921)
			(stroke
				(width 0.508)
				(type default)
			)
			(layer "F.SilkS")
		)
		(fp_line
			(start 1.016 -2.667)
			(end -1.016 -2.667)
			(stroke
				(width 0.1524)
				(type default)
			)
			(layer "F.SilkS")
		)
		(fp_line
			(start 1.016 2.667)
			(end 1.016 -2.667)
			(stroke
				(width 0.1524)
				(type default)
			)
			(layer "F.SilkS")
		)
		(fp_rect
			(start -1.143 3.175)
			(end 1.143 -2.794)
			(stroke
				(width 0)
				(type default)
			)
			(fill no)
			(layer "F.CrtYd")
		)
		(fp_poly
			(pts
				(xy -1.143 -2.794) (xy 1.143 -2.794) (xy 1.143 3.175) (xy -1.143 3.175)
			)
			(stroke
				(width 0)
				(type default)
			)
			(fill no)
			(layer "F.Fab")
		)
		(pad "A" smd rect
			(at 0 -1.6891)
			(size 0.889 1.397)
			(layers "F.Cu" "F.Mask" "F.Paste")
			(net "FAN_TACH3")
		)
		(pad "K" smd rect
			(at 0 1.6891)
			(size 0.889 1.397)
			(layers "F.Cu" "F.Mask" "F.Paste")
			(net "P12V")
		)
	)
)
